# S9S_MB_2U (Grand Teton) — schematic netlist excerpt (pin names and nets, part order shuffled) for the footprints in the layout excerpt that follows; sources: Cadence DE-HDL packaged netlist, KiCad conversion of 03242023_DA0F0TMBIJ0_F0T_Motherboard_J_brd_V01_OCP.brd

PC379  Q_CAP  100NF 50V 10% X7R  pkg C0402  page 297 : A = PVCCD_HV_CPU1 ; B = GND
PC1771  Q_CAPP  560UF 6.3V 20% OSCON  pkg THLF  page 299 : A = PVPP_HBM_CPU1 ; B = GND
H22  HOLE  EMPTY  pkg TH  page 311 : \1\ = NC

(kicad_pcb
	(version 20260206)
	(generator "pcbnew")
	(generator_version "10.0")
	(general
		(thickness 1.6)
		(legacy_teardrops no)
	)
	(paper "A4")
	(title_block
		(title "03242023_DA0F0TMBIJ0_F0T_Motherboard_J_brd_V01_OCP.brd")
		(comment 1 "Grand Teton / footprints 699-701 of 6105")
	)
	(layers
		(0 "F.Cu" signal "TOP")
		(4 "In1.Cu" signal "GND")
		(6 "In2.Cu" signal "IN1")
		(8 "In3.Cu" signal "GND1")
		(10 "In4.Cu" signal "IN2")
		(12 "In5.Cu" signal "GND2")
		(14 "In6.Cu" signal "IN3")
		(16 "In7.Cu" signal "GND3")
		(18 "In8.Cu" signal "VCC")
		(20 "In9.Cu" signal "VCC1")
		(22 "In10.Cu" signal "GND4")
		(24 "In11.Cu" signal "IN4")
		(26 "In12.Cu" signal "GND5")
		(28 "In13.Cu" signal "IN5")
		(30 "In14.Cu" signal "GND6")
		(32 "In15.Cu" signal "IN6")
		(34 "In16.Cu" signal "GND7")
		(2 "B.Cu" signal "BOTTOM")
		(9 "F.Adhes" user "F.Adhesive")
		(11 "B.Adhes" user "B.Adhesive")
		(13 "F.Paste" user "Package Geometry/Pastemask Top")
		(15 "B.Paste" user "Package Geometry/Pastemask Bottom")
		(5 "F.SilkS" user "Ref Des/Silkscreen Top")
		(7 "B.SilkS" user "Ref Des/Silkscreen Bottom")
		(1 "F.Mask" user "Board Geometry/Soldermask Top")
		(3 "B.Mask" user "Board Geometry/Soldermask Bottom")
		(17 "Dwgs.User" user "User.Drawings")
		(19 "Cmts.User" user "User.Comments")
		(21 "Eco1.User" user "User.Eco1")
		(23 "Eco2.User" user "User.Eco2")
		(25 "Edge.Cuts" user "Board Geometry/Outline")
		(27 "Margin" user)
		(31 "F.CrtYd" user "Package Geometry/Place Bound Top")
		(29 "B.CrtYd" user "Package Geometry/Place Bound Bottom")
		(35 "F.Fab" user "Ref Des/Assembly Top")
		(33 "B.Fab" user "Ref Des/Assembly Bottom")
	)
	(footprint ""
		(layer "F.Cu")
		(at 133.725412 -368.24793)
		(property "Reference" "PC1771"
			(at 0 0 0)
			(layer "F.SilkS")
			(hide yes)
			(effects
				(font
					(size 1.27 1.27)
				)
			)
		)
		(property "Value" ""
			(at 0 0 0)
			(layer "F.Fab")
			(effects
				(font
					(size 1.27 1.27)
				)
			)
		)
		(duplicate_pad_numbers_are_jumpers no)
		(fp_line
			(start -3.400044 1.249934)
			(end 3.400044 1.249934)
			(stroke
				(width 0.1524)
				(type default)
			)
			(layer "F.SilkS")
		)
		(fp_circle
			(center 0 1.249934)
			(end 3.400044 1.249934)
			(stroke
				(width 0.1524)
				(type default)
			)
			(fill no)
			(layer "F.SilkS")
		)
		(fp_poly
			(pts
				(arc
					(start 3.400044 1.249934)
					(mid 0 4.649978)
					(end -3.400044 1.249934)
				)
			)
			(stroke
				(width 0)
				(type default)
			)
			(fill yes)
			(layer "F.SilkS")
		)
		(fp_circle
			(center 0 1.249934)
			(end 3.400044 1.249934)
			(stroke
				(width 0.1)
				(type default)
			)
			(fill no)
			(layer "F.Fab")
		)
		(pad "1" thru_hole rect
			(at 0 0)
			(size 1.524 1.524)
			(drill 1.016)
			(layers "*.Cu" "*.Mask")
			(remove_unused_layers no)
			(net "PVPP_HBM_CPU1")
			(clearance 0)
			(padstack
				(mode front_inner_back)
				(layer "Inner"
					(shape circle)
					(size 1.524 1.524)
					(clearance 0)
				)
				(layer "B.Cu"
					(shape rect)
					(size 1.524 1.524)
					(clearance 0)
				)
			)
		)
		(pad "2" thru_hole circle
			(at 0 2.500122)
			(size 1.524 1.524)
			(drill 1.016)
			(layers "*.Cu" "*.Mask")
			(remove_unused_layers no)
			(net "GND")
			(clearance 0)
		)
	)
	(footprint ""
		(layer "F.Cu")
		(at 90.440002 -297.514772)
		(property "Reference" "H22"
			(at -3.582162 -6.911086 0)
			(unlocked yes)
			(layer "F.SilkS")
			(effects
				(font
					(size 0.7874 0.5842)
					(thickness 0.1524)
				)
				(justify left)
			)
		)
		(property "Value" ""
			(at 0 0 0)
			(layer "F.Fab")
			(effects
				(font
					(size 1.27 1.27)
				)
			)
		)
		(duplicate_pad_numbers_are_jumpers no)
		(fp_circle
			(center 0 0)
			(end 2.5273 0)
			(stroke
				(width 0.1524)
				(type default)
			)
			(fill no)
			(layer "F.SilkS")
		)
		(fp_circle
			(center 0 0)
			(end 2.5273 0)
			(stroke
				(width 0.1524)
				(type default)
			)
			(fill no)
			(layer "B.SilkS")
		)
		(fp_circle
			(center 0 0)
			(end 2.5273 0)
			(stroke
				(width 0.1)
				(type default)
			)
			(fill no)
			(layer "B.Fab")
		)
		(fp_circle
			(center 0 0)
			(end 2.5273 0)
			(stroke
				(width 0.1)
				(type default)
			)
			(fill no)
			(layer "F.Fab")
		)
		(pad "" np_thru_hole circle
			(at 0 0)
			(size 3.429 3.429)
			(drill 3.429)
			(layers "*.Cu" "*.Mask")
			(clearance 0.381)
			(thermal_gap 0.381)
		)
	)
	(footprint ""
		(layer "F.Cu")
		(at 73.81748 -162.003486)
		(property "Reference" "PC379"
			(at 0 0 0)
			(layer "F.SilkS")
			(hide yes)
			(effects
				(font
					(size 1.27 1.27)
				)
			)
		)
		(property "Value" ""
			(at 0 0 0)
			(layer "F.Fab")
			(effects
				(font
					(size 1.27 1.27)
				)
			)
		)
		(duplicate_pad_numbers_are_jumpers no)
		(fp_line
			(start -0.7874 -0.4064)
			(end 0.7874 -0.4064)
			(stroke
				(width 0.1524)
				(type default)
			)
			(layer "F.SilkS")
		)
		(fp_line
			(start -0.7874 0.4064)
			(end -0.7874 -0.4064)
			(stroke
				(width 0.1524)
				(type default)
			)
			(layer "F.SilkS")
		)
		(fp_line
			(start 0.7874 -0.4064)
			(end 0.7874 0.4064)
			(stroke
				(width 0.1524)
				(type default)
			)
			(layer "F.SilkS")
		)
		(fp_line
			(start 0.7874 0.4064)
			(end -0.7874 0.4064)
			(stroke
				(width 0.1524)
				(type default)
			)
			(layer "F.SilkS")
		)
		(fp_line
			(start -0.67945 -0.305054)
			(end -0.12065 -0.305054)
			(stroke
				(width 0.1)
				(type default)
			)
			(layer "F.Fab")
		)
		(fp_line
			(start -0.67945 0.3048)
			(end -0.67945 -0.305054)
			(stroke
				(width 0.1)
				(type default)
			)
			(layer "F.Fab")
		)
		(fp_line
			(start -0.12065 -0.305054)
			(end -0.12065 -0.2794)
			(stroke
				(width 0.1)
				(type default)
			)
			(layer "F.Fab")
		)
		(fp_line
			(start -0.12065 -0.2794)
			(end 0.12065 -0.2794)
			(stroke
				(width 0.1)
				(type default)
			)
			(layer "F.Fab")
		)
		(fp_line
			(start -0.12065 0.2794)
			(end -0.12065 0.3048)
			(stroke
				(width 0.1)
				(type default)
			)
			(layer "F.Fab")
		)
		(fp_line
			(start -0.12065 0.3048)
			(end -0.67945 0.3048)
			(stroke
				(width 0.1)
				(type default)
			)
			(layer "F.Fab")
		)
		(fp_line
			(start 0.120396 0.2794)
			(end -0.12065 0.2794)
			(stroke
				(width 0.1)
				(type default)
			)
			(layer "F.Fab")
		)
		(fp_line
			(start 0.120396 0.3048)
			(end 0.120396 0.2794)
			(stroke
				(width 0.1)
				(type default)
			)
			(layer "F.Fab")
		)
		(fp_line
			(start 0.12065 -0.3048)
			(end 0.67945 -0.3048)
			(stroke
				(width 0.1)
				(type default)
			)
			(layer "F.Fab")
		)
		(fp_line
			(start 0.12065 -0.2794)
			(end 0.12065 -0.3048)
			(stroke
				(width 0.1)
				(type default)
			)
			(layer "F.Fab")
		)
		(fp_line
			(start 0.67945 -0.3048)
			(end 0.67945 0.3048)
			(stroke
				(width 0.1)
				(type default)
			)
			(layer "F.Fab")
		)
		(fp_line
			(start 0.67945 0.3048)
			(end 0.120396 0.3048)
			(stroke
				(width 0.1)
				(type default)
			)
			(layer "F.Fab")
		)
		(pad "1" smd circle
			(at -0.40005 0)
			(size 0 0)
			(layers "F.Cu" "F.Mask" "F.Paste")
			(net "PVCCD_HV_CPU1")
		)
		(pad "2" smd circle
			(at 0.40005 0)
			(size 0 0)
			(layers "F.Cu" "F.Mask" "F.Paste")
			(net "GND")
		)
	)
)
